# S9S_MB_2U (Grand Teton) — schematic netlist excerpt (pin names and nets, part order shuffled) for the footprints in the layout excerpt that follows; sources: Cadence DE-HDL packaged netlist, KiCad conversion of 03242023_DA0F0TMBIJ0_F0T_Motherboard_J_brd_V01_OCP.brd

C172  Q_CAP  10UF 6.3V 20% X6S  pkg C0603  page 210 : A = P3V3_AUX_CLK_GEN_VDDA100M_CK440 ; B = GND
R4141  Q_RES  4.7K 5% CHIP  pkg 0402LF  page 146 : A = P3V3_AUX ; B = GPU_3V3IO_RSVD5_FFU_ISO

(kicad_pcb
	(version 20260206)
	(generator "pcbnew")
	(generator_version "10.0")
	(general
		(thickness 1.6)
		(legacy_teardrops no)
	)
	(paper "A4")
	(title_block
		(title "03242023_DA0F0TMBIJ0_F0T_Motherboard_J_brd_V01_OCP.brd")
		(comment 1 "Grand Teton / footprints 3924-3925 of 6105")
	)
	(layers
		(0 "F.Cu" signal "TOP")
		(4 "In1.Cu" signal "GND")
		(6 "In2.Cu" signal "IN1")
		(8 "In3.Cu" signal "GND1")
		(10 "In4.Cu" signal "IN2")
		(12 "In5.Cu" signal "GND2")
		(14 "In6.Cu" signal "IN3")
		(16 "In7.Cu" signal "GND3")
		(18 "In8.Cu" signal "VCC")
		(20 "In9.Cu" signal "VCC1")
		(22 "In10.Cu" signal "GND4")
		(24 "In11.Cu" signal "IN4")
		(26 "In12.Cu" signal "GND5")
		(28 "In13.Cu" signal "IN5")
		(30 "In14.Cu" signal "GND6")
		(32 "In15.Cu" signal "IN6")
		(34 "In16.Cu" signal "GND7")
		(2 "B.Cu" signal "BOTTOM")
		(9 "F.Adhes" user "F.Adhesive")
		(11 "B.Adhes" user "B.Adhesive")
		(13 "F.Paste" user "Package Geometry/Pastemask Top")
		(15 "B.Paste" user "Package Geometry/Pastemask Bottom")
		(5 "F.SilkS" user "Ref Des/Silkscreen Top")
		(7 "B.SilkS" user "Ref Des/Silkscreen Bottom")
		(1 "F.Mask" user "Board Geometry/Soldermask Top")
		(3 "B.Mask" user "Board Geometry/Soldermask Bottom")
		(17 "Dwgs.User" user "User.Drawings")
		(19 "Cmts.User" user "User.Comments")
		(21 "Eco1.User" user "User.Eco1")
		(23 "Eco2.User" user "User.Eco2")
		(25 "Edge.Cuts" user "Board Geometry/Outline")
		(27 "Margin" user)
		(31 "F.CrtYd" user "Package Geometry/Place Bound Top")
		(29 "B.CrtYd" user "Package Geometry/Place Bound Bottom")
		(35 "F.Fab" user "Ref Des/Assembly Top")
		(33 "B.Fab" user "Ref Des/Assembly Bottom")
	)
	(footprint ""
		(layer "F.Cu")
		(at 266.032234 -94.192598 90)
		(property "Reference" "C172"
			(at 0 0 90)
			(layer "F.SilkS")
			(hide yes)
			(effects
				(font
					(size 1.27 1.27)
				)
			)
		)
		(property "Value" ""
			(at 0 0 90)
			(layer "F.Fab")
			(effects
				(font
					(size 1.27 1.27)
				)
			)
		)
		(duplicate_pad_numbers_are_jumpers no)
		(fp_line
			(start 1.2954 -0.5842)
			(end 1.2954 0.5842)
			(stroke
				(width 0.1524)
				(type default)
			)
			(layer "F.SilkS")
		)
		(fp_line
			(start 0 -0.5842)
			(end 0 0.5842)
			(stroke
				(width 0.1524)
				(type default)
			)
			(layer "F.SilkS")
		)
		(fp_line
			(start -1.2954 -0.5842)
			(end 1.2954 -0.5842)
			(stroke
				(width 0.1524)
				(type default)
			)
			(layer "F.SilkS")
		)
		(fp_line
			(start 1.2954 0.5842)
			(end -1.2954 0.5842)
			(stroke
				(width 0.1524)
				(type default)
			)
			(layer "F.SilkS")
		)
		(fp_line
			(start -1.2954 0.5842)
			(end -1.2954 -0.5842)
			(stroke
				(width 0.1524)
				(type default)
			)
			(layer "F.SilkS")
		)
		(fp_line
			(start 0.8636 -0.4572)
			(end 0.8636 -0.4064)
			(stroke
				(width 0.1)
				(type default)
			)
			(layer "F.Fab")
		)
		(fp_line
			(start -0.8636 -0.4572)
			(end 0.8636 -0.4572)
			(stroke
				(width 0.1)
				(type default)
			)
			(layer "F.Fab")
		)
		(fp_line
			(start 1.1938 -0.4064)
			(end 1.1938 0.4064)
			(stroke
				(width 0.1)
				(type default)
			)
			(layer "F.Fab")
		)
		(fp_line
			(start 0.8636 -0.4064)
			(end 1.1938 -0.4064)
			(stroke
				(width 0.1)
				(type default)
			)
			(layer "F.Fab")
		)
		(fp_line
			(start -0.8636 -0.4064)
			(end -0.8636 -0.4572)
			(stroke
				(width 0.1)
				(type default)
			)
			(layer "F.Fab")
		)
		(fp_line
			(start -1.1938 -0.4064)
			(end -0.8636 -0.4064)
			(stroke
				(width 0.1)
				(type default)
			)
			(layer "F.Fab")
		)
		(fp_line
			(start 1.1938 0.4064)
			(end 0.8636 0.4064)
			(stroke
				(width 0.1)
				(type default)
			)
			(layer "F.Fab")
		)
		(fp_line
			(start 0.8636 0.4064)
			(end 0.8636 0.4572)
			(stroke
				(width 0.1)
				(type default)
			)
			(layer "F.Fab")
		)
		(fp_line
			(start -0.8636 0.4064)
			(end -1.1938 0.4064)
			(stroke
				(width 0.1)
				(type default)
			)
			(layer "F.Fab")
		)
		(fp_line
			(start -1.1938 0.4064)
			(end -1.1938 -0.4064)
			(stroke
				(width 0.1)
				(type default)
			)
			(layer "F.Fab")
		)
		(fp_line
			(start 0.8636 0.4572)
			(end -0.8636 0.4572)
			(stroke
				(width 0.1)
				(type default)
			)
			(layer "F.Fab")
		)
		(fp_line
			(start -0.8636 0.4572)
			(end -0.8636 0.4064)
			(stroke
				(width 0.1)
				(type default)
			)
			(layer "F.Fab")
		)
		(pad "1" smd rect
			(at -0.7366 0)
			(size 0.7112 0.8128)
			(layers "F.Cu" "F.Mask" "F.Paste")
			(net "P3V3_AUX_CLK_GEN_VDDA100M_CK440")
		)
		(pad "2" smd rect
			(at 0.7366 0)
			(size 0.7112 0.8128)
			(layers "F.Cu" "F.Mask" "F.Paste")
			(net "GND")
		)
	)
	(footprint ""
		(layer "F.Cu")
		(at 298.66082 -421.41521 90)
		(property "Reference" "R4141"
			(at 0 0 90)
			(layer "F.SilkS")
			(hide yes)
			(effects
				(font
					(size 1.27 1.27)
				)
			)
		)
		(property "Value" ""
			(at 0 0 90)
			(layer "F.Fab")
			(effects
				(font
					(size 1.27 1.27)
				)
			)
		)
		(duplicate_pad_numbers_are_jumpers no)
		(fp_line
			(start 0.7874 -0.4064)
			(end 0.7874 0.4064)
			(stroke
				(width 0.1524)
				(type default)
			)
			(layer "F.SilkS")
		)
		(fp_line
			(start -0.7874 -0.4064)
			(end 0.7874 -0.4064)
			(stroke
				(width 0.1524)
				(type default)
			)
			(layer "F.SilkS")
		)
		(fp_line
			(start 0.7874 0.4064)
			(end -0.7874 0.4064)
			(stroke
				(width 0.1524)
				(type default)
			)
			(layer "F.SilkS")
		)
		(fp_line
			(start -0.7874 0.4064)
			(end -0.7874 -0.4064)
			(stroke
				(width 0.1524)
				(type default)
			)
			(layer "F.SilkS")
		)
		(fp_line
			(start -0.12065 -0.305054)
			(end -0.12065 -0.2794)
			(stroke
				(width 0.1)
				(type default)
			)
			(layer "F.Fab")
		)
		(fp_line
			(start -0.67945 -0.305054)
			(end -0.12065 -0.305054)
			(stroke
				(width 0.1)
				(type default)
			)
			(layer "F.Fab")
		)
		(fp_line
			(start 0.67945 -0.3048)
			(end 0.67945 0.3048)
			(stroke
				(width 0.1)
				(type default)
			)
			(layer "F.Fab")
		)
		(fp_line
			(start 0.12065 -0.3048)
			(end 0.67945 -0.3048)
			(stroke
				(width 0.1)
				(type default)
			)
			(layer "F.Fab")
		)
		(fp_line
			(start 0.12065 -0.2794)
			(end 0.12065 -0.3048)
			(stroke
				(width 0.1)
				(type default)
			)
			(layer "F.Fab")
		)
		(fp_line
			(start -0.12065 -0.2794)
			(end 0.12065 -0.2794)
			(stroke
				(width 0.1)
				(type default)
			)
			(layer "F.Fab")
		)
		(fp_line
			(start 0.120396 0.2794)
			(end -0.12065 0.2794)
			(stroke
				(width 0.1)
				(type default)
			)
			(layer "F.Fab")
		)
		(fp_line
			(start -0.12065 0.2794)
			(end -0.12065 0.3048)
			(stroke
				(width 0.1)
				(type default)
			)
			(layer "F.Fab")
		)
		(fp_line
			(start 0.67945 0.3048)
			(end 0.120396 0.3048)
			(stroke
				(width 0.1)
				(type default)
			)
			(layer "F.Fab")
		)
		(fp_line
			(start 0.120396 0.3048)
			(end 0.120396 0.2794)
			(stroke
				(width 0.1)
				(type default)
			)
			(layer "F.Fab")
		)
		(fp_line
			(start -0.12065 0.3048)
			(end -0.67945 0.3048)
			(stroke
				(width 0.1)
				(type default)
			)
			(layer "F.Fab")
		)
		(fp_line
			(start -0.67945 0.3048)
			(end -0.67945 -0.305054)
			(stroke
				(width 0.1)
				(type default)
			)
			(layer "F.Fab")
		)
		(pad "1" smd circle
			(at -0.40005 0 90)
			(size 0 0)
			(layers "F.Cu" "F.Mask" "F.Paste")
			(net "P3V3_AUX")
		)
		(pad "2" smd circle
			(at 0.40005 0 90)
			(size 0 0)
			(layers "F.Cu" "F.Mask" "F.Paste")
			(net "GPU_3V3IO_RSVD5_FFU_ISO")
		)
	)
)
